# BASEBOARD_FAB2 (Tioga Pass) — schematic netlist excerpt (pin names and nets, part order shuffled) for the footprints in the layout excerpt that follows; sources: Cadence DE-HDL packaged netlist, KiCad conversion of Wiwynn_Tioga_Pass_MB.brd

C3P28  CAP  0.22UF 16V 10% X7R  pkg 0402  page 107 : A = P3E_CPU0_PE1_SS_TXN<4> ; B = P3E_CPU0_PE1_PCH_TXN<4>
R1U30  RES  1.00K 1% CHIP  pkg 0402  page 152 : A = PD_DIR_2 ; B = GND
R9L11  RES  1.00K 1% CHIP  pkg 0402  page 100 : A = M_K_VREF ; B = GND

(kicad_pcb
	(version 20260206)
	(generator "pcbnew")
	(generator_version "10.0")
	(general
		(thickness 1.6)
		(legacy_teardrops no)
	)
	(paper "A4")
	(title_block
		(title "Wiwynn_Tioga_Pass_MB.brd")
		(comment 1 "Tioga Pass / footprints 4583-4585 of 4770")
	)
	(layers
		(0 "F.Cu" signal "TOP")
		(4 "In1.Cu" signal "L2GND")
		(6 "In2.Cu" signal "L3")
		(8 "In3.Cu" signal "L4GND")
		(10 "In4.Cu" signal "L5")
		(12 "In5.Cu" signal "L6GND")
		(14 "In6.Cu" signal "L7VCC")
		(16 "In7.Cu" signal "L8VCC")
		(18 "In8.Cu" signal "L9GND")
		(20 "In9.Cu" signal "L10")
		(22 "In10.Cu" signal "L11GND")
		(24 "In11.Cu" signal "L12")
		(26 "In12.Cu" signal "L13GND")
		(2 "B.Cu" signal "BOTTOM")
		(9 "F.Adhes" user "F.Adhesive")
		(11 "B.Adhes" user "B.Adhesive")
		(13 "F.Paste" user "Package Geometry/Pastemask Top")
		(15 "B.Paste" user "Package Geometry/Pastemask Bottom")
		(5 "F.SilkS" user "Ref Des/Silkscreen Top")
		(7 "B.SilkS" user "Ref Des/Silkscreen Bottom")
		(1 "F.Mask" user "Board Geometry/Soldermask Top")
		(3 "B.Mask" user "Board Geometry/Soldermask Bottom")
		(17 "Dwgs.User" user "User.Drawings")
		(19 "Cmts.User" user "User.Comments")
		(21 "Eco1.User" user "User.Eco1")
		(23 "Eco2.User" user "User.Eco2")
		(25 "Edge.Cuts" user "Board Geometry/Outline")
		(27 "Margin" user)
		(31 "F.CrtYd" user "Package Geometry/Place Bound Top")
		(29 "B.CrtYd" user "Package Geometry/Place Bound Bottom")
		(35 "F.Fab" user "Ref Des/Assembly Top")
		(33 "B.Fab" user "Ref Des/Assembly Bottom")
	)
	(footprint ""
		(layer "B.Cu")
		(at 29.690568 -135.763)
		(property "Reference" "R9L11"
			(at 0 0 0)
			(layer "B.SilkS")
			(hide yes)
			(effects
				(font
					(size 1.27 1.27)
				)
				(justify mirror)
			)
		)
		(property "Value" ""
			(at 0 0 0)
			(layer "B.Fab")
			(effects
				(font
					(size 1.27 1.27)
				)
				(justify mirror)
			)
		)
		(duplicate_pad_numbers_are_jumpers no)
		(fp_poly
			(pts
				(xy 0.2794 -0.1016) (xy -0.2794 -0.1016) (xy -0.2794 0.9906) (xy 0.2794 0.9906)
			)
			(stroke
				(width 0)
				(type default)
			)
			(fill no)
			(layer "B.CrtYd")
		)
		(fp_line
			(start -0.2794 -0.1016)
			(end 0.2794 -0.1016)
			(stroke
				(width 0.1)
				(type default)
			)
			(layer "B.Fab")
		)
		(fp_line
			(start -0.2794 0.9906)
			(end -0.2794 -0.1016)
			(stroke
				(width 0.1)
				(type default)
			)
			(layer "B.Fab")
		)
		(fp_line
			(start 0.2794 -0.1016)
			(end 0.2794 0.9906)
			(stroke
				(width 0.1)
				(type default)
			)
			(layer "B.Fab")
		)
		(fp_line
			(start 0.2794 0.9906)
			(end -0.2794 0.9906)
			(stroke
				(width 0.1)
				(type default)
			)
			(layer "B.Fab")
		)
		(pad "1" smd rect
			(at 0 0 180)
			(size 0.508 0.508)
			(layers "B.Cu" "B.Mask" "B.Paste")
			(net "M_K_VREF")
		)
		(pad "2" smd rect
			(at 0 0.889 180)
			(size 0.508 0.508)
			(layers "B.Cu" "B.Mask" "B.Paste")
			(net "GND")
		)
		(zone
			(layer "B.Cu")
			(hatch none 0.5)
			(connect_pads
				(clearance 0)
			)
			(min_thickness 0.25)
			(keepout
				(tracks allowed)
				(vias not_allowed)
				(pads allowed)
				(copperpour not_allowed)
				(footprints allowed)
			)
			(placement
				(enabled no)
				(sheetname "")
			)
			(fill
				(thermal_gap 0.5)
				(thermal_bridge_width 0.5)
				(island_removal_mode 0)
			)
			(polygon
				(pts
					(xy 29.944568 -135.509) (xy 29.436568 -135.509) (xy 29.436568 -135.128) (xy 29.944568 -135.128)
				)
			)
		)
		(zone
			(layer "B.Cu")
			(hatch none 0.5)
			(connect_pads
				(clearance 0)
			)
			(min_thickness 0.25)
			(keepout
				(tracks not_allowed)
				(vias allowed)
				(pads allowed)
				(copperpour not_allowed)
				(footprints allowed)
			)
			(placement
				(enabled no)
				(sheetname "")
			)
			(fill
				(thermal_gap 0.5)
				(thermal_bridge_width 0.5)
				(island_removal_mode 0)
			)
			(polygon
				(pts
					(xy 29.944568 -135.128) (xy 29.436568 -135.128) (xy 29.436568 -135.509) (xy 29.944568 -135.509)
				)
			)
		)
	)
	(footprint ""
		(layer "B.Cu")
		(at 351.421192 -77.834236 180)
		(property "Reference" "C3P28"
			(at 0 0 0)
			(layer "B.SilkS")
			(hide yes)
			(effects
				(font
					(size 1.27 1.27)
				)
				(justify mirror)
			)
		)
		(property "Value" ""
			(at 0 0 0)
			(layer "B.Fab")
			(effects
				(font
					(size 1.27 1.27)
				)
				(justify mirror)
			)
		)
		(duplicate_pad_numbers_are_jumpers no)
		(fp_poly
			(pts
				(xy -0.3048 -0.1016) (xy -0.3048 0.9906) (xy 0.3048 0.9906) (xy 0.3048 -0.1016)
			)
			(stroke
				(width 0)
				(type default)
			)
			(fill no)
			(layer "B.CrtYd")
		)
		(fp_line
			(start 0.3048 0.9906)
			(end -0.3048 0.9906)
			(stroke
				(width 0.1)
				(type default)
			)
			(layer "B.Fab")
		)
		(fp_line
			(start 0.3048 -0.1016)
			(end 0.3048 0.9906)
			(stroke
				(width 0.1)
				(type default)
			)
			(layer "B.Fab")
		)
		(fp_line
			(start -0.3048 0.9906)
			(end -0.3048 -0.1016)
			(stroke
				(width 0.1)
				(type default)
			)
			(layer "B.Fab")
		)
		(fp_line
			(start -0.3048 -0.1016)
			(end 0.3048 -0.1016)
			(stroke
				(width 0.1)
				(type default)
			)
			(layer "B.Fab")
		)
		(pad "1" smd rect
			(at 0 0)
			(size 0.508 0.508)
			(layers "B.Cu" "B.Mask" "B.Paste")
			(net "P3E_CPU0_PE1_SS_TXN<4>")
		)
		(pad "2" smd rect
			(at 0 0.889)
			(size 0.508 0.508)
			(layers "B.Cu" "B.Mask" "B.Paste")
			(net "P3E_CPU0_PE1_PCH_TXN<4>")
		)
		(zone
			(layer "B.Cu")
			(hatch none 0.5)
			(connect_pads
				(clearance 0)
			)
			(min_thickness 0.25)
			(keepout
				(tracks not_allowed)
				(vias allowed)
				(pads allowed)
				(copperpour not_allowed)
				(footprints allowed)
			)
			(placement
				(enabled no)
				(sheetname "")
			)
			(fill
				(thermal_gap 0.5)
				(thermal_bridge_width 0.5)
				(island_removal_mode 0)
			)
			(polygon
				(pts
					(xy 351.167192 -78.469236) (xy 351.675192 -78.469236) (xy 351.675192 -78.088236) (xy 351.167192 -78.088236)
				)
			)
		)
		(zone
			(layer "B.Cu")
			(hatch none 0.5)
			(connect_pads
				(clearance 0)
			)
			(min_thickness 0.25)
			(keepout
				(tracks allowed)
				(vias not_allowed)
				(pads allowed)
				(copperpour not_allowed)
				(footprints allowed)
			)
			(placement
				(enabled no)
				(sheetname "")
			)
			(fill
				(thermal_gap 0.5)
				(thermal_bridge_width 0.5)
				(island_removal_mode 0)
			)
			(polygon
				(pts
					(xy 351.167192 -78.088236) (xy 351.675192 -78.088236) (xy 351.675192 -78.469236) (xy 351.167192 -78.469236)
				)
			)
		)
	)
	(footprint ""
		(layer "B.Cu")
		(at 440.458606 -16.164306 90)
		(property "Reference" "R1U30"
			(at 0 0 90)
			(layer "B.SilkS")
			(hide yes)
			(effects
				(font
					(size 1.27 1.27)
				)
				(justify mirror)
			)
		)
		(property "Value" ""
			(at 0 0 90)
			(layer "B.Fab")
			(effects
				(font
					(size 1.27 1.27)
				)
				(justify mirror)
			)
		)
		(duplicate_pad_numbers_are_jumpers no)
		(fp_poly
			(pts
				(xy 0.2794 -0.1016) (xy -0.2794 -0.1016) (xy -0.2794 0.9906) (xy 0.2794 0.9906)
			)
			(stroke
				(width 0)
				(type default)
			)
			(fill no)
			(layer "B.CrtYd")
		)
		(fp_line
			(start 0.2794 -0.1016)
			(end 0.2794 0.9906)
			(stroke
				(width 0.1)
				(type default)
			)
			(layer "B.Fab")
		)
		(fp_line
			(start -0.2794 -0.1016)
			(end 0.2794 -0.1016)
			(stroke
				(width 0.1)
				(type default)
			)
			(layer "B.Fab")
		)
		(fp_line
			(start 0.2794 0.9906)
			(end -0.2794 0.9906)
			(stroke
				(width 0.1)
				(type default)
			)
			(layer "B.Fab")
		)
		(fp_line
			(start -0.2794 0.9906)
			(end -0.2794 -0.1016)
			(stroke
				(width 0.1)
				(type default)
			)
			(layer "B.Fab")
		)
		(pad "1" smd rect
			(at 0 0 270)
			(size 0.508 0.508)
			(layers "B.Cu" "B.Mask" "B.Paste")
			(net "PD_DIR_2")
		)
		(pad "2" smd rect
			(at 0 0.889 270)
			(size 0.508 0.508)
			(layers "B.Cu" "B.Mask" "B.Paste")
			(net "GND")
		)
		(zone
			(layer "B.Cu")
			(hatch none 0.5)
			(connect_pads
				(clearance 0)
			)
			(min_thickness 0.25)
			(keepout
				(tracks allowed)
				(vias not_allowed)
				(pads allowed)
				(copperpour not_allowed)
				(footprints allowed)
			)
			(placement
				(enabled no)
				(sheetname "")
			)
			(fill
				(thermal_gap 0.5)
				(thermal_bridge_width 0.5)
				(island_removal_mode 0)
			)
			(polygon
				(pts
					(xy 440.712606 -16.418306) (xy 440.712606 -15.910306) (xy 441.093606 -15.910306) (xy 441.093606 -16.418306)
				)
			)
		)
		(zone
			(layer "B.Cu")
			(hatch none 0.5)
			(connect_pads
				(clearance 0)
			)
			(min_thickness 0.25)
			(keepout
				(tracks not_allowed)
				(vias allowed)
				(pads allowed)
				(copperpour not_allowed)
				(footprints allowed)
			)
			(placement
				(enabled no)
				(sheetname "")
			)
			(fill
				(thermal_gap 0.5)
				(thermal_bridge_width 0.5)
				(island_removal_mode 0)
			)
			(polygon
				(pts
					(xy 441.093606 -16.418306) (xy 441.093606 -15.910306) (xy 440.712606 -15.910306) (xy 440.712606 -16.418306)
				)
			)
		)
	)
)
